# T6G (Grand Teton) — schematic netlist excerpt (pin names and nets, part order shuffled) for the footprints in the layout excerpt that follows; sources: Cadence DE-HDL packaged netlist, KiCad conversion of 04192023_DAF0TMB3IC0_F0TG_MB_C_brd_V02_OCP.brd

PC179  Q_CAP  560PF 50V 10% EMPTY  pkg C0402  page 194 : A = SW_PVDDCR_CPU0_P0_SW2 ; B = SW_PVDDCR_CPU0_P0_SW2_RC
C2158  Q_CAP  22UF 4V 20% X6S  pkg C0402  page 68 : A = PVDD11_S3_P0 ; B = GND

(kicad_pcb
	(version 20260206)
	(generator "pcbnew")
	(generator_version "10.0")
	(general
		(thickness 1.6)
		(legacy_teardrops no)
	)
	(paper "A4")
	(title_block
		(title "04192023_DAF0TMB3IC0_F0TG_MB_C_brd_V02_OCP.brd")
		(comment 1 "Grand Teton / footprints 2085-2086 of 8354")
	)
	(layers
		(0 "F.Cu" signal "TOP")
		(4 "In1.Cu" signal "GND")
		(6 "In2.Cu" signal "IN1")
		(8 "In3.Cu" signal "GND1")
		(10 "In4.Cu" signal "IN2")
		(12 "In5.Cu" signal "GND2")
		(14 "In6.Cu" signal "IN3")
		(16 "In7.Cu" signal "GND3")
		(18 "In8.Cu" signal "VCC")
		(20 "In9.Cu" signal "VCC1")
		(22 "In10.Cu" signal "GND4")
		(24 "In11.Cu" signal "IN4")
		(26 "In12.Cu" signal "GND5")
		(28 "In13.Cu" signal "IN5")
		(30 "In14.Cu" signal "GND6")
		(32 "In15.Cu" signal "IN6")
		(34 "In16.Cu" signal "GND7")
		(2 "B.Cu" signal "BOTTOM")
		(9 "F.Adhes" user "F.Adhesive")
		(11 "B.Adhes" user "B.Adhesive")
		(13 "F.Paste" user "Package Geometry/Pastemask Top")
		(15 "B.Paste" user "Package Geometry/Pastemask Bottom")
		(5 "F.SilkS" user "Ref Des/Silkscreen Top")
		(7 "B.SilkS" user "Ref Des/Silkscreen Bottom")
		(1 "F.Mask" user "Board Geometry/Soldermask Top")
		(3 "B.Mask" user "Board Geometry/Soldermask Bottom")
		(17 "Dwgs.User" user "User.Drawings")
		(19 "Cmts.User" user "User.Comments")
		(21 "Eco1.User" user "User.Eco1")
		(23 "Eco2.User" user "User.Eco2")
		(25 "Edge.Cuts" user "Board Geometry/Outline")
		(27 "Margin" user)
		(31 "F.CrtYd" user "Package Geometry/Place Bound Top")
		(29 "B.CrtYd" user "Package Geometry/Place Bound Bottom")
		(35 "F.Fab" user "Ref Des/Assembly Top")
		(33 "B.Fab" user "Ref Des/Assembly Bottom")
	)
	(footprint ""
		(layer "F.Cu")
		(at 359.417112 -261.747762 -90)
		(property "Reference" "C2158"
			(at 0 0 270)
			(layer "F.SilkS")
			(hide yes)
			(effects
				(font
					(size 1.27 1.27)
				)
			)
		)
		(property "Value" ""
			(at 0 0 270)
			(layer "F.Fab")
			(effects
				(font
					(size 1.27 1.27)
				)
			)
		)
		(duplicate_pad_numbers_are_jumpers no)
		(fp_line
			(start -0.7874 0.4064)
			(end -0.7874 -0.4064)
			(stroke
				(width 0.1524)
				(type default)
			)
			(layer "F.SilkS")
		)
		(fp_line
			(start 0.7874 0.4064)
			(end -0.7874 0.4064)
			(stroke
				(width 0.1524)
				(type default)
			)
			(layer "F.SilkS")
		)
		(fp_line
			(start -0.7874 -0.4064)
			(end 0.7874 -0.4064)
			(stroke
				(width 0.1524)
				(type default)
			)
			(layer "F.SilkS")
		)
		(fp_line
			(start 0.7874 -0.4064)
			(end 0.7874 0.4064)
			(stroke
				(width 0.1524)
				(type default)
			)
			(layer "F.SilkS")
		)
		(fp_line
			(start -0.67945 0.3048)
			(end -0.67945 -0.305054)
			(stroke
				(width 0.1)
				(type default)
			)
			(layer "F.Fab")
		)
		(fp_line
			(start -0.12065 0.3048)
			(end -0.67945 0.3048)
			(stroke
				(width 0.1)
				(type default)
			)
			(layer "F.Fab")
		)
		(fp_line
			(start 0.120396 0.3048)
			(end 0.120396 0.2794)
			(stroke
				(width 0.1)
				(type default)
			)
			(layer "F.Fab")
		)
		(fp_line
			(start 0.67945 0.3048)
			(end 0.120396 0.3048)
			(stroke
				(width 0.1)
				(type default)
			)
			(layer "F.Fab")
		)
		(fp_line
			(start -0.12065 0.2794)
			(end -0.12065 0.3048)
			(stroke
				(width 0.1)
				(type default)
			)
			(layer "F.Fab")
		)
		(fp_line
			(start 0.120396 0.2794)
			(end -0.12065 0.2794)
			(stroke
				(width 0.1)
				(type default)
			)
			(layer "F.Fab")
		)
		(fp_line
			(start -0.12065 -0.2794)
			(end 0.12065 -0.2794)
			(stroke
				(width 0.1)
				(type default)
			)
			(layer "F.Fab")
		)
		(fp_line
			(start 0.12065 -0.2794)
			(end 0.12065 -0.3048)
			(stroke
				(width 0.1)
				(type default)
			)
			(layer "F.Fab")
		)
		(fp_line
			(start 0.12065 -0.3048)
			(end 0.67945 -0.3048)
			(stroke
				(width 0.1)
				(type default)
			)
			(layer "F.Fab")
		)
		(fp_line
			(start 0.67945 -0.3048)
			(end 0.67945 0.3048)
			(stroke
				(width 0.1)
				(type default)
			)
			(layer "F.Fab")
		)
		(fp_line
			(start -0.67945 -0.305054)
			(end -0.12065 -0.305054)
			(stroke
				(width 0.1)
				(type default)
			)
			(layer "F.Fab")
		)
		(fp_line
			(start -0.12065 -0.305054)
			(end -0.12065 -0.2794)
			(stroke
				(width 0.1)
				(type default)
			)
			(layer "F.Fab")
		)
		(pad "1" smd circle
			(at -0.40005 0 270)
			(size 0 0)
			(layers "F.Cu" "F.Mask" "F.Paste")
			(net "PVDD11_S3_P0")
		)
		(pad "2" smd circle
			(at 0.40005 0 270)
			(size 0 0)
			(layers "F.Cu" "F.Mask" "F.Paste")
			(net "GND")
		)
	)
	(footprint ""
		(layer "F.Cu")
		(at 376.369072 -185.748168)
		(property "Reference" "PC179"
			(at 0 0 0)
			(layer "F.SilkS")
			(hide yes)
			(effects
				(font
					(size 1.27 1.27)
				)
			)
		)
		(property "Value" ""
			(at 0 0 0)
			(layer "F.Fab")
			(effects
				(font
					(size 1.27 1.27)
				)
			)
		)
		(duplicate_pad_numbers_are_jumpers no)
		(fp_line
			(start -0.7874 -0.4064)
			(end 0.7874 -0.4064)
			(stroke
				(width 0.1524)
				(type default)
			)
			(layer "F.SilkS")
		)
		(fp_line
			(start -0.7874 0.4064)
			(end -0.7874 -0.4064)
			(stroke
				(width 0.1524)
				(type default)
			)
			(layer "F.SilkS")
		)
		(fp_line
			(start 0.7874 -0.4064)
			(end 0.7874 0.4064)
			(stroke
				(width 0.1524)
				(type default)
			)
			(layer "F.SilkS")
		)
		(fp_line
			(start 0.7874 0.4064)
			(end -0.7874 0.4064)
			(stroke
				(width 0.1524)
				(type default)
			)
			(layer "F.SilkS")
		)
		(fp_line
			(start -0.67945 -0.305054)
			(end -0.12065 -0.305054)
			(stroke
				(width 0.1)
				(type default)
			)
			(layer "F.Fab")
		)
		(fp_line
			(start -0.67945 0.3048)
			(end -0.67945 -0.305054)
			(stroke
				(width 0.1)
				(type default)
			)
			(layer "F.Fab")
		)
		(fp_line
			(start -0.12065 -0.305054)
			(end -0.12065 -0.2794)
			(stroke
				(width 0.1)
				(type default)
			)
			(layer "F.Fab")
		)
		(fp_line
			(start -0.12065 -0.2794)
			(end 0.12065 -0.2794)
			(stroke
				(width 0.1)
				(type default)
			)
			(layer "F.Fab")
		)
		(fp_line
			(start -0.12065 0.2794)
			(end -0.12065 0.3048)
			(stroke
				(width 0.1)
				(type default)
			)
			(layer "F.Fab")
		)
		(fp_line
			(start -0.12065 0.3048)
			(end -0.67945 0.3048)
			(stroke
				(width 0.1)
				(type default)
			)
			(layer "F.Fab")
		)
		(fp_line
			(start 0.120396 0.2794)
			(end -0.12065 0.2794)
			(stroke
				(width 0.1)
				(type default)
			)
			(layer "F.Fab")
		)
		(fp_line
			(start 0.120396 0.3048)
			(end 0.120396 0.2794)
			(stroke
				(width 0.1)
				(type default)
			)
			(layer "F.Fab")
		)
		(fp_line
			(start 0.12065 -0.3048)
			(end 0.67945 -0.3048)
			(stroke
				(width 0.1)
				(type default)
			)
			(layer "F.Fab")
		)
		(fp_line
			(start 0.12065 -0.2794)
			(end 0.12065 -0.3048)
			(stroke
				(width 0.1)
				(type default)
			)
			(layer "F.Fab")
		)
		(fp_line
			(start 0.67945 -0.3048)
			(end 0.67945 0.3048)
			(stroke
				(width 0.1)
				(type default)
			)
			(layer "F.Fab")
		)
		(fp_line
			(start 0.67945 0.3048)
			(end 0.120396 0.3048)
			(stroke
				(width 0.1)
				(type default)
			)
			(layer "F.Fab")
		)
		(pad "1" smd circle
			(at -0.40005 0)
			(size 0 0)
			(layers "F.Cu" "F.Mask" "F.Paste")
			(net "SW_PVDDCR_CPU0_P0_SW2")
		)
		(pad "2" smd circle
			(at 0.40005 0)
			(size 0 0)
			(layers "F.Cu" "F.Mask" "F.Paste")
			(net "SW_PVDDCR_CPU0_P0_SW2_RC")
		)
	)
)
